(kicad_pcb
	(version 20241229)
	(generator "pcbnew")
	(generator_version "9.0")
	(general
		(thickness 1.61)
		(legacy_teardrops no)
	)
	(paper "A3")
	(title_block
		(title "RDIMM DDR5 Tester")
		(date "2026-05-21")
		(rev "2.2.0")
		(company "Antmicro")
		(comment 9 "footprints 494-498 of 796")
	)
	(layers
		(0 "F.Cu" signal)
		(4 "In1.Cu" power)
		(6 "In2.Cu" mixed)
		(8 "In3.Cu" power)
		(10 "In4.Cu" mixed)
		(12 "In5.Cu" power)
		(14 "In6.Cu" mixed)
		(16 "In7.Cu" power)
		(18 "In8.Cu" power)
		(20 "In9.Cu" mixed)
		(22 "In10.Cu" power)
		(2 "B.Cu" signal)
		(9 "F.Adhes" user "F.Adhesive")
		(11 "B.Adhes" user "B.Adhesive")
		(13 "F.Paste" user)
		(15 "B.Paste" user)
		(5 "F.SilkS" user "F.Silkscreen")
		(7 "B.SilkS" user "B.Silkscreen")
		(1 "F.Mask" user)
		(3 "B.Mask" user)
		(17 "Dwgs.User" user "User.Drawings")
		(19 "Cmts.User" user "User.Comments")
		(21 "Eco1.User" user "User.Eco1")
		(23 "Eco2.User" user "User.Eco2")
		(25 "Edge.Cuts" user)
		(27 "Margin" user)
		(31 "F.CrtYd" user "F.Courtyard")
		(29 "B.CrtYd" user "B.Courtyard")
		(35 "F.Fab" user)
		(33 "B.Fab" user)
	)
	(footprint "antmicro-footprints:C_0402_1005Metric"
		(layer "B.Cu")
		(at 148.275 193.875 180)
		(descr "Capacitor SMD 0402")
		(tags "capacitor SMD 0402")
		(property "Reference" "C170"
			(at -4.035 -0.525 0)
			(layer "B.SilkS")
			(effects
				(font
					(size 0.7 0.7)
					(thickness 0.15)
				)
				(justify left bottom mirror)
			)
		)
		(property "Value" "C_100n_0402"
			(at -1.022927 -2.155213 0)
			(layer "B.Fab")
			(effects
				(font
					(size 0.7 0.7)
					(thickness 0.15)
				)
				(justify left bottom mirror)
			)
		)
		(property "Datasheet" "https://www.murata.com/products/productdetail?partno=GRM155R61H104KE14%23"
			(at 0 0 180)
			(layer "F.Fab")
			(hide yes)
			(effects
				(font
					(size 1.27 1.27)
					(thickness 0.15)
				)
			)
		)
		(property "Manufacturer" "Murata"
			(at 0 0 180)
			(unlocked yes)
			(layer "B.Fab")
			(hide yes)
			(effects
				(font
					(size 1 1)
					(thickness 0.15)
				)
				(justify mirror)
			)
		)
		(property "MPN" "GRM155R61H104KE14D"
			(at 0 0 180)
			(unlocked yes)
			(layer "B.Fab")
			(hide yes)
			(effects
				(font
					(size 1 1)
					(thickness 0.15)
				)
				(justify mirror)
			)
		)
		(property "Val" "100n"
			(at 0 0 180)
			(unlocked yes)
			(layer "B.Fab")
			(hide yes)
			(effects
				(font
					(size 1 1)
					(thickness 0.15)
				)
				(justify mirror)
			)
		)
		(property "License" "Apache-2.0"
			(at 0 0 180)
			(unlocked yes)
			(layer "B.Fab")
			(hide yes)
			(effects
				(font
					(size 1 1)
					(thickness 0.15)
				)
				(justify mirror)
			)
		)
		(property "Author" "Antmicro"
			(at 0 0 180)
			(unlocked yes)
			(layer "B.Fab")
			(hide yes)
			(effects
				(font
					(size 1 1)
					(thickness 0.15)
				)
				(justify mirror)
			)
		)
		(property "Voltage" "50V"
			(at 0 0 180)
			(unlocked yes)
			(layer "B.Fab")
			(hide yes)
			(effects
				(font
					(size 1 1)
					(thickness 0.15)
				)
				(justify mirror)
			)
		)
		(property "Dielectric" "X5R"
			(at 0 0 180)
			(unlocked yes)
			(layer "B.Fab")
			(hide yes)
			(effects
				(font
					(size 1 1)
					(thickness 0.15)
				)
				(justify mirror)
			)
		)
		(sheetname "/Supply/")
		(sheetfile "supply.kicad_sch")
		(attr smd)
		(fp_rect
			(start -0.925 0.47)
			(end 0.925 -0.47)
			(stroke
				(width 0.05)
				(type default)
			)
			(fill no)
			(layer "B.CrtYd")
		)
		(fp_line
			(start 0.504 0.25)
			(end 0.504 -0.248)
			(stroke
				(width 0.15)
				(type solid)
			)
			(layer "B.Fab")
		)
		(fp_line
			(start 0.504 -0.248)
			(end -0.494 -0.248)
			(stroke
				(width 0.15)
				(type solid)
			)
			(layer "B.Fab")
		)
		(fp_line
			(start -0.494 0.25)
			(end 0.504 0.25)
			(stroke
				(width 0.15)
				(type solid)
			)
			(layer "B.Fab")
		)
		(fp_line
			(start -0.494 -0.248)
			(end -0.494 0.25)
			(stroke
				(width 0.15)
				(type solid)
			)
			(layer "B.Fab")
		)
		(fp_text user "${REFERENCE}"
			(at -0.939 -4.599 0)
			(layer "B.Fab")
			(effects
				(font
					(size 0.7 0.7)
					(thickness 0.15)
				)
				(justify left bottom mirror)
			)
		)
		(fp_text user "Author: Antmicro"
			(at -0.939 -3.399 0)
			(layer "B.Fab")
			(effects
				(font
					(size 0.7 0.7)
					(thickness 0.15)
				)
				(justify left bottom mirror)
			)
		)
		(fp_text user "License: Apache-2.0"
			(at -0.939 -5.799 0)
			(layer "B.Fab")
			(effects
				(font
					(size 0.7 0.7)
					(thickness 0.15)
				)
				(justify left bottom mirror)
			)
		)
		(pad "1" smd roundrect
			(at -0.48 0 180)
			(size 0.59 0.64)
			(layers "B.Cu" "B.Mask" "B.Paste")
			(roundrect_rratio 0.25)
			(net 1 "GND")
			(pintype "passive")
		)
		(pad "2" smd roundrect
			(at 0.48 0 180)
			(size 0.59 0.64)
			(layers "B.Cu" "B.Mask" "B.Paste")
			(roundrect_rratio 0.25)
			(net 10 "+12V")
			(pintype "passive")
		)
	)
	(footprint "antmicro-footprints:R_0402_1005Metric"
		(layer "B.Cu")
		(at 242.97 132.855 -90)
		(descr "Resistor SMD 0402")
		(tags "resistor SMD 0402")
		(property "Reference" "R122"
			(at -3.855 -0.33 90)
			(layer "B.SilkS")
			(effects
				(font
					(size 0.7 0.7)
					(thickness 0.15)
				)
				(justify left bottom mirror)
			)
		)
		(property "Value" "R_4k7_0402"
			(at -2.4 -0.65 90)
			(layer "B.Fab")
			(effects
				(font
					(size 0.7 0.7)
					(thickness 0.15)
				)
				(justify left bottom mirror)
			)
		)
		(property "Datasheet" "https://www.bourns.com/docs/product-datasheets/cr.pdf"
			(at 0 0 270)
			(layer "F.Fab")
			(hide yes)
			(effects
				(font
					(size 1.27 1.27)
					(thickness 0.15)
				)
			)
		)
		(property "Manufacturer" "Bourns"
			(at 0 0 270)
			(unlocked yes)
			(layer "B.Fab")
			(hide yes)
			(effects
				(font
					(size 1 1)
					(thickness 0.15)
				)
				(justify mirror)
			)
		)
		(property "MPN" "CR0402-FX-4701GLF"
			(at 0 0 270)
			(unlocked yes)
			(layer "B.Fab")
			(hide yes)
			(effects
				(font
					(size 1 1)
					(thickness 0.15)
				)
				(justify mirror)
			)
		)
		(property "Val" "4k7"
			(at 0 0 270)
			(unlocked yes)
			(layer "B.Fab")
			(hide yes)
			(effects
				(font
					(size 1 1)
					(thickness 0.15)
				)
				(justify mirror)
			)
		)
		(property "License" "Apache-2.0"
			(at 0 0 270)
			(unlocked yes)
			(layer "B.Fab")
			(hide yes)
			(effects
				(font
					(size 1 1)
					(thickness 0.15)
				)
				(justify mirror)
			)
		)
		(property "Author" "Antmicro"
			(at 0 0 270)
			(unlocked yes)
			(layer "B.Fab")
			(hide yes)
			(effects
				(font
					(size 1 1)
					(thickness 0.15)
				)
				(justify mirror)
			)
		)
		(property "Tolerance" "1%"
			(at 0 0 270)
			(unlocked yes)
			(layer "B.Fab")
			(hide yes)
			(effects
				(font
					(size 1 1)
					(thickness 0.15)
				)
				(justify mirror)
			)
		)
		(sheetname "/I^{2}C + I3C/")
		(sheetfile "i2c.kicad_sch")
		(attr smd)
		(fp_rect
			(start -0.925 0.47)
			(end 0.925 -0.47)
			(stroke
				(width 0.05)
				(type default)
			)
			(fill no)
			(layer "B.CrtYd")
		)
		(fp_rect
			(start -0.5 0.25)
			(end 0.5 -0.25)
			(stroke
				(width 0.15)
				(type solid)
			)
			(fill no)
			(layer "B.Fab")
		)
		(fp_text user "License: Apache-2.0"
			(at -0.95 -5.169 90)
			(layer "B.Fab")
			(effects
				(font
					(size 0.7 0.7)
					(thickness 0.15)
				)
				(justify left bottom mirror)
			)
		)
		(fp_text user "Author: Antmicro"
			(at -0.95 -4.169 90)
			(layer "B.Fab")
			(effects
				(font
					(size 0.7 0.7)
					(thickness 0.15)
				)
				(justify left bottom mirror)
			)
		)
		(fp_text user "${REFERENCE}"
			(at -0.95 -3.168 90)
			(layer "B.Fab")
			(effects
				(font
					(size 0.7 0.7)
					(thickness 0.15)
				)
				(justify left bottom mirror)
			)
		)
		(pad "1" smd roundrect
			(at -0.48 0 270)
			(size 0.59 0.64)
			(layers "B.Cu" "B.Mask" "B.Paste")
			(roundrect_rratio 0.25)
			(net 151 "+3V3")
			(pintype "passive")
		)
		(pad "2" smd roundrect
			(at 0.48 0 270)
			(size 0.59 0.64)
			(layers "B.Cu" "B.Mask" "B.Paste")
			(roundrect_rratio 0.25)
			(net 465 "/FPGA banks HD/FPGA_DDR.SCL")
			(pintype "passive")
		)
	)
	(footprint "antmicro-footprints:R_0402_1005Metric"
		(layer "B.Cu")
		(at 260.5055 158.671 90)
		(descr "Resistor SMD 0402")
		(tags "resistor SMD 0402")
		(property "Reference" "R169"
			(at -3.729 0.4445 90)
			(layer "B.SilkS")
			(effects
				(font
					(size 0.7 0.7)
					(thickness 0.15)
				)
				(justify right bottom mirror)
			)
		)
		(property "Value" "R_0R_0402"
			(at -1.011843 -1.772047 90)
			(layer "B.Fab")
			(effects
				(font
					(size 0.7 0.7)
					(thickness 0.15)
				)
				(justify right bottom mirror)
			)
		)
		(property "Datasheet" "https://industrial.panasonic.com/cdbs/www-data/pdf/RDA0000/AOA0000C301.pdf"
			(at 0 0 90)
			(layer "F.Fab")
			(hide yes)
			(effects
				(font
					(size 1.27 1.27)
					(thickness 0.15)
				)
			)
		)
		(property "Manufacturer" "Panasonic"
			(at 0 0 90)
			(unlocked yes)
			(layer "B.Fab")
			(hide yes)
			(effects
				(font
					(size 1 1)
					(thickness 0.15)
				)
				(justify mirror)
			)
		)
		(property "MPN" "ERJ2GE0R00X"
			(at 0 0 90)
			(unlocked yes)
			(layer "B.Fab")
			(hide yes)
			(effects
				(font
					(size 1 1)
					(thickness 0.15)
				)
				(justify mirror)
			)
		)
		(property "Val" "0R"
			(at 0 0 90)
			(unlocked yes)
			(layer "B.Fab")
			(hide yes)
			(effects
				(font
					(size 1 1)
					(thickness 0.15)
				)
				(justify mirror)
			)
		)
		(property "License" "Apache-2.0"
			(at 0 0 90)
			(unlocked yes)
			(layer "B.Fab")
			(hide yes)
			(effects
				(font
					(size 1 1)
					(thickness 0.15)
				)
				(justify mirror)
			)
		)
		(property "Author" "Antmicro"
			(at 0 0 90)
			(unlocked yes)
			(layer "B.Fab")
			(hide yes)
			(effects
				(font
					(size 1 1)
					(thickness 0.15)
				)
				(justify mirror)
			)
		)
		(property "Tolerance" "~"
			(at 0 0 90)
			(unlocked yes)
			(layer "B.Fab")
			(hide yes)
			(effects
				(font
					(size 1 1)
					(thickness 0.15)
				)
				(justify mirror)
			)
		)
		(property "Current" "1A"
			(at 0 0 90)
			(unlocked yes)
			(layer "B.Fab")
			(hide yes)
			(effects
				(font
					(size 1 1)
					(thickness 0.15)
				)
				(justify mirror)
			)
		)
		(sheetname "/Supply/DC-DC IO/")
		(sheetfile "dc-dc-io.kicad_sch")
		(attr smd exclude_from_bom dnp)
		(fp_rect
			(start -0.925 0.47)
			(end 0.925 -0.47)
			(stroke
				(width 0.05)
				(type default)
			)
			(fill no)
			(layer "B.CrtYd")
		)
		(fp_rect
			(start -0.5 0.25)
			(end 0.5 -0.25)
			(stroke
				(width 0.15)
				(type solid)
			)
			(fill no)
			(layer "B.Fab")
		)
		(fp_text user "${REFERENCE}"
			(at -0.95 -3.168 270)
			(layer "B.Fab")
			(effects
				(font
					(size 0.7 0.7)
					(thickness 0.15)
				)
				(justify left bottom mirror)
			)
		)
		(fp_text user "Author: Antmicro"
			(at -0.95 -4.169 270)
			(layer "B.Fab")
			(effects
				(font
					(size 0.7 0.7)
					(thickness 0.15)
				)
				(justify left bottom mirror)
			)
		)
		(fp_text user "License: Apache-2.0"
			(at -0.95 -5.169 270)
			(layer "B.Fab")
			(effects
				(font
					(size 0.7 0.7)
					(thickness 0.15)
				)
				(justify left bottom mirror)
			)
		)
		(pad "1" smd roundrect
			(at -0.48 0 90)
			(size 0.59 0.64)
			(layers "B.Cu" "B.Mask" "B.Paste")
			(roundrect_rratio 0.25)
			(net 1 "GND")
			(pintype "passive")
		)
		(pad "2" smd roundrect
			(at 0.48 0 90)
			(size 0.59 0.64)
			(layers "B.Cu" "B.Mask" "B.Paste")
			(roundrect_rratio 0.25)
			(net 719 "/Supply/DC-DC IO/FB8")
			(pintype "passive")
		)
	)
	(footprint "antmicro-footprints:C_0402_1005Metric_EIA"
		(layer "B.Cu")
		(at 200.498 155 180)
		(descr "Capacitor SMD 0402 (1005 Metric), square (rectangular) end terminal, IPC_7351 nominal, (Body size source: IPC-SM-782 page 76, https://www.pcb-3d.com/wordpress/wp-content/uploads/ipc-sm-782a_amendment_1_and_2.pdf)")
		(tags "capacitor 0402")
		(property "Reference" "C15"
			(at -1.177 -1.425 0)
			(layer "B.SilkS")
			(effects
				(font
					(size 0.7 0.7)
					(thickness 0.15)
				)
				(justify left bottom mirror)
			)
		)
		(property "Value" "C_100n_0402"
			(at 0 -1.169 0)
			(layer "B.Fab")
			(effects
				(font
					(size 0.7 0.7)
					(thickness 0.15)
				)
				(justify left bottom mirror)
			)
		)
		(property "Datasheet" "https://www.murata.com/products/productdetail?partno=GRM155R61H104KE14%23"
			(at 0 0 180)
			(layer "F.Fab")
			(hide yes)
			(effects
				(font
					(size 1.27 1.27)
					(thickness 0.15)
				)
			)
		)
		(property "MPN" "GRM155R61H104KE14D"
			(at 0 0 180)
			(unlocked yes)
			(layer "B.Fab")
			(hide yes)
			(effects
				(font
					(size 1 1)
					(thickness 0.15)
				)
				(justify mirror)
			)
		)
		(property "Manufacturer" "Murata"
			(at 0 0 180)
			(unlocked yes)
			(layer "B.Fab")
			(hide yes)
			(effects
				(font
					(size 1 1)
					(thickness 0.15)
				)
				(justify mirror)
			)
		)
		(property "License" "Apache-2.0"
			(at 0 0 180)
			(unlocked yes)
			(layer "B.Fab")
			(hide yes)
			(effects
				(font
					(size 1 1)
					(thickness 0.15)
				)
				(justify mirror)
			)
		)
		(property "Author" "Antmicro"
			(at 0 0 180)
			(unlocked yes)
			(layer "B.Fab")
			(hide yes)
			(effects
				(font
					(size 1 1)
					(thickness 0.15)
				)
				(justify mirror)
			)
		)
		(property "Val" "100n"
			(at 0 0 180)
			(unlocked yes)
			(layer "B.Fab")
			(hide yes)
			(effects
				(font
					(size 1 1)
					(thickness 0.15)
				)
				(justify mirror)
			)
		)
		(property "Voltage" "50V"
			(at 0 0 180)
			(unlocked yes)
			(layer "B.Fab")
			(hide yes)
			(effects
				(font
					(size 1 1)
					(thickness 0.15)
				)
				(justify mirror)
			)
		)
		(property "Dielectric" "X5R"
			(at 0 0 180)
			(unlocked yes)
			(layer "B.Fab")
			(hide yes)
			(effects
				(font
					(size 1 1)
					(thickness 0.15)
				)
				(justify mirror)
			)
		)
		(sheetname "/FPGA power/")
		(sheetfile "fpga-power.kicad_sch")
		(attr smd)
		(fp_rect
			(start -0.95 0.45)
			(end 0.95 -0.45)
			(stroke
				(width 0.05)
				(type default)
			)
			(fill no)
			(layer "B.CrtYd")
		)
		(fp_line
			(start 0.498 0.25)
			(end 0.498 -0.248)
			(stroke
				(width 0.15)
				(type solid)
			)
			(layer "B.Fab")
		)
		(fp_line
			(start 0.498 -0.248)
			(end -0.5 -0.248)
			(stroke
				(width 0.15)
				(type solid)
			)
			(layer "B.Fab")
		)
		(fp_line
			(start -0.5 0.25)
			(end 0.498 0.25)
			(stroke
				(width 0.15)
				(type solid)
			)
			(layer "B.Fab")
		)
		(fp_line
			(start -0.5 -0.248)
			(end -0.5 0.25)
			(stroke
				(width 0.15)
				(type solid)
			)
			(layer "B.Fab")
		)
		(fp_text user "License: Apache-2.0"
			(at -0.9656 -4.369 0)
			(layer "B.Fab")
			(effects
				(font
					(size 0.7 0.7)
					(thickness 0.15)
				)
				(justify left bottom mirror)
			)
		)
		(fp_text user "${REFERENCE}"
			(at -0.9656 -3.169 0)
			(layer "B.Fab")
			(effects
				(font
					(size 0.7 0.7)
					(thickness 0.15)
				)
				(justify left bottom mirror)
			)
		)
		(fp_text user "Author: Antmicro"
			(at -0.9656 -5.569 0)
			(layer "B.Fab")
			(effects
				(font
					(size 0.7 0.7)
					(thickness 0.15)
				)
				(justify left bottom mirror)
			)
		)
		(pad "1" smd roundrect
			(at -0.5 0 90)
			(size 0.6 0.6)
			(layers "B.Cu" "B.Mask" "B.Paste")
			(roundrect_rratio 0.25)
			(net 1 "GND")
			(pintype "passive")
		)
		(pad "2" smd roundrect
			(at 0.498 0 180)
			(size 0.6 0.6)
			(layers "B.Cu" "B.Mask" "B.Paste")
			(roundrect_rratio 0.25)
			(net 797 "+1V8")
			(pintype "passive")
		)
	)
	(footprint "antmicro-footprints:C_0402_1005Metric_EIA"
		(layer "B.Cu")
		(at 187 150.5 -90)
		(descr "Capacitor SMD 0402 (1005 Metric), square (rectangular) end terminal, IPC_7351 nominal, (Body size source: IPC-SM-782 page 76, https://www.pcb-3d.com/wordpress/wp-content/uploads/ipc-sm-782a_amendment_1_and_2.pdf)")
		(tags "capacitor 0402")
		(property "Reference" "C81"
			(at -11.525 30.625 90)
			(layer "B.SilkS")
			(effects
				(font
					(size 0.7 0.7)
					(thickness 0.15)
				)
				(justify left bottom mirror)
			)
		)
		(property "Value" "C_1u_25V_0402"
			(at 0 -1.169 90)
			(layer "B.Fab")
			(effects
				(font
					(size 0.7 0.7)
					(thickness 0.15)
				)
				(justify left bottom mirror)
			)
		)
		(property "Datasheet" "https://www.murata.com/products/productdetail?partno=GRM155R61E105KE11%23"
			(at 0 0 270)
			(layer "F.Fab")
			(hide yes)
			(effects
				(font
					(size 1.27 1.27)
					(thickness 0.15)
				)
			)
		)
		(property "MPN" "GRM155R61E105KE11J"
			(at 0 0 270)
			(unlocked yes)
			(layer "B.Fab")
			(hide yes)
			(effects
				(font
					(size 1 1)
					(thickness 0.15)
				)
				(justify mirror)
			)
		)
		(property "Manufacturer" "Murata"
			(at 0 0 270)
			(unlocked yes)
			(layer "B.Fab")
			(hide yes)
			(effects
				(font
					(size 1 1)
					(thickness 0.15)
				)
				(justify mirror)
			)
		)
		(property "License" "Apache-2.0"
			(at 0 0 270)
			(unlocked yes)
			(layer "B.Fab")
			(hide yes)
			(effects
				(font
					(size 1 1)
					(thickness 0.15)
				)
				(justify mirror)
			)
		)
		(property "Author" "Antmicro"
			(at 0 0 270)
			(unlocked yes)
			(layer "B.Fab")
			(hide yes)
			(effects
				(font
					(size 1 1)
					(thickness 0.15)
				)
				(justify mirror)
			)
		)
		(property "Val" "1u"
			(at 0 0 270)
			(unlocked yes)
			(layer "B.Fab")
			(hide yes)
			(effects
				(font
					(size 1 1)
					(thickness 0.15)
				)
				(justify mirror)
			)
		)
		(property "Voltage" "25V"
			(at 0 0 270)
			(unlocked yes)
			(layer "B.Fab")
			(hide yes)
			(effects
				(font
					(size 1 1)
					(thickness 0.15)
				)
				(justify mirror)
			)
		)
		(property "Dielectric" "X5R"
			(at 0 0 270)
			(unlocked yes)
			(layer "B.Fab")
			(hide yes)
			(effects
				(font
					(size 1 1)
					(thickness 0.15)
				)
				(justify mirror)
			)
		)
		(sheetname "/FPGA power/")
		(sheetfile "fpga-power.kicad_sch")
		(attr smd)
		(fp_rect
			(start -0.95 0.45)
			(end 0.95 -0.45)
			(stroke
				(width 0.05)
				(type default)
			)
			(fill no)
			(layer "B.CrtYd")
		)
		(fp_line
			(start -0.5 0.25)
			(end 0.498 0.25)
			(stroke
				(width 0.15)
				(type solid)
			)
			(layer "B.Fab")
		)
		(fp_line
			(start 0.498 0.25)
			(end 0.498 -0.248)
			(stroke
				(width 0.15)
				(type solid)
			)
			(layer "B.Fab")
		)
		(fp_line
			(start -0.5 -0.248)
			(end -0.5 0.25)
			(stroke
				(width 0.15)
				(type solid)
			)
			(layer "B.Fab")
		)
		(fp_line
			(start 0.498 -0.248)
			(end -0.5 -0.248)
			(stroke
				(width 0.15)
				(type solid)
			)
			(layer "B.Fab")
		)
		(fp_text user "License: Apache-2.0"
			(at -0.9656 -4.369 90)
			(layer "B.Fab")
			(effects
				(font
					(size 0.7 0.7)
					(thickness 0.15)
				)
				(justify left bottom mirror)
			)
		)
		(fp_text user "${REFERENCE}"
			(at -0.9656 -3.169 90)
			(layer "B.Fab")
			(effects
				(font
					(size 0.7 0.7)
					(thickness 0.15)
				)
				(justify left bottom mirror)
			)
		)
		(fp_text user "Author: Antmicro"
			(at -0.9656 -5.569 90)
			(layer "B.Fab")
			(effects
				(font
					(size 0.7 0.7)
					(thickness 0.15)
				)
				(justify left bottom mirror)
			)
		)
		(pad "1" smd roundrect
			(at -0.5 0 180)
			(size 0.6 0.6)
			(layers "B.Cu" "B.Mask" "B.Paste")
			(roundrect_rratio 0.25)
			(net 1 "GND")
			(pintype "passive")
		)
		(pad "2" smd roundrect
			(at 0.498 0 270)
			(size 0.6 0.6)
			(layers "B.Cu" "B.Mask" "B.Paste")
			(roundrect_rratio 0.25)
			(net 797 "+1V8")
			(pintype "passive")
		)
	)
)
